FILE_TYPE = CONNECTIVITY;
{Allegro Design Entry HDL 17.2-2016 S081 (4005846) 1/11/2022}
"PAGE_NUMBER" = 101;
0"NC";
1"P3V3_AUX\g";
2"P12V_S3_AUX_CPU1_NVDIMM\g";
3"P12V_S3_AUX_CPU1_NVDIMM\g";
4"P3V3_AUX\g";
5"GND\g";
6"GND\g";
7"GND\g";
8"GND\g";
9"GND\g";
10"M_B_CPU1_SA_DQ<31:0>";
11"M_B_CPU1_SA_CB<7:0>";
12"M_B_CPU1_SB_CB<7:0>";
13"M_B_CPU1_SA_CA<6:0>";
14"M_B_CPU1_SB_CA<6:0>";
15"M_B_CPU1_SB_DQ<31:0>";
16"M_B_CPU1_SB_DQS_DP<9:0>";
17"M_B_CPU1_SA_DQS_DP<9:0>";
18"M_B_CPU1_SB_DQS_DN<9:0>";
19"M_B_CPU1_SA_DQS_DN<9:0>";
20"I3C_SPD_DDRABCD_CPU1_LVC1_SCL";
21"PD_CHB_CPU1_DIMM2_SAA";
22"I3C_SPD_DDRABCD_CPU1_LVC1_SDA";
23"I3C_SPD_DDRABCD_CPU1_LVC1_SCL_R4";
24"M_B_CPU1_ALERT_N";
25"RST_M_AB_CPU1_FPGA_N";
26"PWRGD_CHB_CPU1_DIMM2";
27"TP_CHB_CPU1_DIMM2_FRU_6";
28"TP_CHB_CPU1_DIMM2_FRU_5";
29"M_B_CPU1_SA_DQS_DN<8>";
30"M_B_CPU1_SA_DQS_DN<9>";
31"M_B_CPU1_SA_DQS_DN<7>";
32"M_B_CPU1_SA_DQS_DN<6>";
33"M_B_CPU1_SA_DQS_DN<5>";
34"M_B_CPU1_SA_DQS_DN<4>";
35"M_B_CPU1_SA_DQS_DN<3>";
36"M_B_CPU1_SA_DQS_DN<2>";
37"M_B_CPU1_SA_DQS_DN<1>";
38"M_B_CPU1_SA_DQS_DN<0>";
39"M_B_CPU1_SB_DQS_DN<9>";
40"M_B_CPU1_SB_DQS_DN<8>";
41"M_B_CPU1_SB_DQS_DN<7>";
42"M_B_CPU1_SB_DQS_DN<6>";
43"M_B_CPU1_SB_DQS_DN<5>";
44"M_B_CPU1_SB_DQS_DN<4>";
45"M_B_CPU1_SB_DQS_DN<3>";
46"M_B_CPU1_SB_DQS_DN<2>";
47"M_B_CPU1_SB_DQS_DN<1>";
48"M_B_CPU1_SB_DQS_DN<0>";
49"M_B_CPU1_SA_DQS_DP<9>";
50"M_B_CPU1_SA_DQS_DP<8>";
51"M_B_CPU1_SA_DQS_DP<7>";
52"M_B_CPU1_SA_DQS_DP<6>";
53"M_B_CPU1_SA_DQS_DP<5>";
54"M_B_CPU1_SA_DQS_DP<4>";
55"M_B_CPU1_SA_DQS_DP<3>";
56"M_B_CPU1_SA_DQS_DP<2>";
57"M_B_CPU1_SA_DQS_DP<1>";
58"M_B_CPU1_SA_DQS_DP<0>";
59"M_B_CPU1_SB_DQS_DP<9>";
60"M_B_CPU1_SB_DQS_DP<8>";
61"M_B_CPU1_SB_DQS_DP<7>";
62"M_B_CPU1_SB_DQS_DP<6>";
63"M_B_CPU1_SB_DQS_DP<5>";
64"M_B_CPU1_SB_DQS_DP<4>";
65"M_B_CPU1_SB_DQS_DP<3>";
66"M_B_CPU1_SB_DQS_DP<2>";
67"M_B_CPU1_SB_DQS_DP<1>";
68"M_B_CPU1_SB_DQS_DP<0>";
69"M_B_CPU1_SB_CB<3>";
70"M_B_CPU1_SB_DQ<13>";
71"M_B_CPU1_SB_DQ<16>";
72"M_B_CPU1_SA_DQ<21>";
73"M_B_CPU1_SA_DQ<20>";
74"M_B_CPU1_SA_DQ<19>";
75"M_B_CPU1_SA_DQ<7>";
76"M_B_CPU1_SA_DQ<8>";
77"M_B_CPU1_SB_DQ<14>";
78"M_B_CPU1_SB_DQ<12>";
79"TP_CHB_CPU1_DIMM2_FRU_0";
80"TP_CHB_CPU1_DIMM2_FRU_1";
81"TP_CHB_CPU1_DIMM2_FRU_2";
82"TP_CHB_CPU1_DIMM2_FRU_3";
83"TP_CHB_CPU1_DIMM2_FRU_4";
84"M_B_CPU1_SB_PAR";
85"M_B_CPU1_SA_PAR";
86"M_B_CPU1_SB_RSP<1>";
87"M_B_CPU1_SA_RSP<1>";
88"M_B_CPU1_SB_DQ<0>";
89"M_B_CPU1_SB_DQ<1>";
90"M_B_CPU1_SB_DQ<2>";
91"M_B_CPU1_SB_DQ<3>";
92"M_B_CPU1_SB_DQ<4>";
93"M_B_CPU1_SB_DQ<5>";
94"M_B_CPU1_SB_DQ<6>";
95"M_B_CPU1_SB_DQ<7>";
96"M_B_CPU1_SB_DQ<8>";
97"M_B_CPU1_SB_DQ<9>";
98"M_B_CPU1_SB_DQ<10>";
99"M_B_CPU1_SB_DQ<11>";
100"M_B_CPU1_SB_DQ<15>";
101"M_B_CPU1_SB_DQ<17>";
102"M_B_CPU1_SB_DQ<18>";
103"M_B_CPU1_SB_DQ<19>";
104"M_B_CPU1_SB_DQ<20>";
105"M_B_CPU1_SB_DQ<21>";
106"M_B_CPU1_SB_DQ<22>";
107"M_B_CPU1_SB_DQ<23>";
108"M_B_CPU1_SB_DQ<24>";
109"M_B_CPU1_SB_DQ<25>";
110"M_B_CPU1_SB_DQ<26>";
111"M_B_CPU1_SB_DQ<27>";
112"M_B_CPU1_SB_DQ<28>";
113"M_B_CPU1_SB_DQ<29>";
114"M_B_CPU1_SB_DQ<30>";
115"M_B_CPU1_SB_DQ<31>";
116"M_B_CPU1_SA_DQ<0>";
117"M_B_CPU1_SA_DQ<1>";
118"M_B_CPU1_SA_DQ<2>";
119"M_B_CPU1_SA_DQ<3>";
120"M_B_CPU1_SA_DQ<4>";
121"M_B_CPU1_SA_DQ<5>";
122"M_B_CPU1_SA_DQ<6>";
123"M_B_CPU1_SA_DQ<9>";
124"M_B_CPU1_SA_DQ<10>";
125"M_B_CPU1_SA_DQ<11>";
126"M_B_CPU1_SA_DQ<12>";
127"M_B_CPU1_SA_DQ<13>";
128"M_B_CPU1_SA_DQ<14>";
129"M_B_CPU1_SA_DQ<15>";
130"M_B_CPU1_SA_DQ<16>";
131"M_B_CPU1_SA_DQ<17>";
132"M_B_CPU1_SA_DQ<18>";
133"M_B_CPU1_SA_DQ<22>";
134"M_B_CPU1_SA_DQ<23>";
135"M_B_CPU1_SA_DQ<24>";
136"M_B_CPU1_SA_DQ<25>";
137"M_B_CPU1_SA_DQ<26>";
138"M_B_CPU1_SA_DQ<27>";
139"M_B_CPU1_SA_DQ<28>";
140"M_B_CPU1_SA_DQ<29>";
141"M_B_CPU1_SA_DQ<30>";
142"M_B_CPU1_SB_CS_N<3>";
143"M_B_CPU1_SA_CS_N<3>";
144"M_B_CPU1_SB_CS_N<2>";
145"M_B_CPU1_SA_CS_N<2>";
146"M_B_CPU1_CLK_DP<1>";
147"M_B_CPU1_CLK_DN<1>";
148"M_B_CPU1_SB_CB<0>";
149"M_B_CPU1_SB_CB<1>";
150"M_B_CPU1_SB_CB<2>";
151"M_B_CPU1_SB_CB<4>";
152"M_B_CPU1_SB_CB<5>";
153"M_B_CPU1_SB_CB<6>";
154"M_B_CPU1_SA_CB<0>";
155"M_B_CPU1_SA_CB<2>";
156"M_B_CPU1_SA_CB<3>";
157"M_B_CPU1_SA_CB<5>";
158"M_B_CPU1_SA_CB<6>";
159"M_B_CPU1_SB_CA<6>";
160"M_B_CPU1_SA_CA<6>";
161"M_B_CPU1_SB_CA<5>";
162"M_B_CPU1_SA_CA<5>";
163"M_B_CPU1_SB_CA<4>";
164"M_B_CPU1_SA_CA<4>";
165"M_B_CPU1_SB_CA<3>";
166"M_B_CPU1_SA_CA<3>";
167"M_B_CPU1_SB_CA<2>";
168"M_B_CPU1_SA_CA<2>";
169"M_B_CPU1_SB_CA<1>";
170"M_B_CPU1_SA_CA<1>";
171"M_B_CPU1_SB_CA<0>";
172"M_B_CPU1_SA_CA<0>";
173"M_B_CPU1_SB_CB<7>";
174"M_B_CPU1_SA_CB<1>";
175"M_B_CPU1_SA_CB<4>";
176"M_B_CPU1_SA_CB<7>";
177"M_B_CPU1_SA_DQ<31>";
178"PD_CHB_CPU1_DIMM2_SAA";
%"TAP"
"1","(-2625,4100)","0","standard","I100";
;
CDS_LIB"standard"
BODY_TYPE"PLUMBING"
HDL_TAP"TRUE";
"B \NAC \NWC"10;
"S \NAC"
BN"20"73;
%"TAP"
"1","(-2625,4150)","0","standard","I101";
;
CDS_LIB"standard"
BODY_TYPE"PLUMBING"
HDL_TAP"TRUE";
"B \NAC \NWC"10;
"S \NAC"
BN"21"72;
%"TAP"
"1","(-2625,4200)","0","standard","I102";
;
CDS_LIB"standard"
BODY_TYPE"PLUMBING"
HDL_TAP"TRUE";
"B \NAC \NWC"10;
"S \NAC"
BN"22"133;
%"TAP"
"1","(-2625,4250)","0","standard","I103";
;
CDS_LIB"standard"
BODY_TYPE"PLUMBING"
HDL_TAP"TRUE";
"B \NAC \NWC"10;
"S \NAC"
BN"23"134;
%"TAP"
"1","(-2625,4300)","0","standard","I104";
;
CDS_LIB"standard"
BODY_TYPE"PLUMBING"
HDL_TAP"TRUE";
"B \NAC \NWC"10;
"S \NAC"
BN"24"135;
%"TAP"
"1","(-4275,4350)","2","standard","I106";
;
CDS_LIB"standard"
BODY_TYPE"PLUMBING"
HDL_TAP"TRUE";
"B \NAC \NWC"13;
"S \NAC"
BN"0"172;
%"TAP"
"1","(-4275,4400)","2","standard","I107";
;
CDS_LIB"standard"
BODY_TYPE"PLUMBING"
HDL_TAP"TRUE";
"B \NAC \NWC"13;
"S \NAC"
BN"1"170;
%"TAP"
"1","(-4275,4550)","2","standard","I108";
;
CDS_LIB"standard"
BODY_TYPE"PLUMBING"
HDL_TAP"TRUE";
"B \NAC \NWC"13;
"S \NAC"
BN"4"164;
%"TAP"
"1","(-4275,4500)","2","standard","I109";
;
CDS_LIB"standard"
BODY_TYPE"PLUMBING"
HDL_TAP"TRUE";
"B \NAC \NWC"13;
"S \NAC"
BN"3"166;
%"TAP"
"1","(-4275,4450)","2","standard","I110";
;
CDS_LIB"standard"
BODY_TYPE"PLUMBING"
HDL_TAP"TRUE";
"B \NAC \NWC"13;
"S \NAC"
BN"2"168;
%"TAP"
"1","(-4275,4600)","2","standard","I111";
;
CDS_LIB"standard"
BODY_TYPE"PLUMBING"
HDL_TAP"TRUE";
"B \NAC \NWC"13;
"S \NAC"
BN"5"162;
%"TAP"
"1","(-4275,4650)","2","standard","I112";
;
CDS_LIB"standard"
BODY_TYPE"PLUMBING"
HDL_TAP"TRUE";
"B \NAC \NWC"13;
"S \NAC"
BN"6"160;
%"TAP"
"1","(-2625,4350)","0","standard","I113";
;
CDS_LIB"standard"
BODY_TYPE"PLUMBING"
HDL_TAP"TRUE";
"B \NAC \NWC"10;
"S \NAC"
BN"25"136;
%"TAP"
"1","(-2625,4400)","0","standard","I114";
;
CDS_LIB"standard"
BODY_TYPE"PLUMBING"
HDL_TAP"TRUE";
"B \NAC \NWC"10;
"S \NAC"
BN"26"137;
%"TAP"
"1","(-2625,4450)","0","standard","I115";
;
CDS_LIB"standard"
BODY_TYPE"PLUMBING"
HDL_TAP"TRUE";
"B \NAC \NWC"10;
"S \NAC"
BN"27"138;
%"TAP"
"1","(-2625,4500)","0","standard","I116";
;
CDS_LIB"standard"
BODY_TYPE"PLUMBING"
HDL_TAP"TRUE";
"B \NAC \NWC"10;
"S \NAC"
BN"28"139;
%"TAP"
"1","(-2625,4600)","0","standard","I117";
;
CDS_LIB"standard"
BODY_TYPE"PLUMBING"
HDL_TAP"TRUE";
"B \NAC \NWC"10;
"S \NAC"
BN"30"141;
%"TAP"
"1","(-2625,4550)","0","standard","I118";
;
CDS_LIB"standard"
BODY_TYPE"PLUMBING"
HDL_TAP"TRUE";
"B \NAC \NWC"10;
"S \NAC"
BN"29"140;
%"TAP"
"1","(-2625,4650)","0","standard","I119";
;
CDS_LIB"standard"
BODY_TYPE"PLUMBING"
HDL_TAP"TRUE";
"B \NAC \NWC"10;
"S \NAC"
BN"31"177;
%"UNIVERSAL_GND"
"1","(-900,400)","0","logical_power","I120";
;
HDL_POWER"GND"
CDS_LIB"logical_power";
"A"5;
%"Q_CAP"
"1","(-900,775)","0","pure_quanta","I121";
;
PART_NUMBER"CH5221MEB00"
TOLERANCE"20%"
PACK_TYPE"C0402"
MATERIAL"X6S"
VOLTAGE"6.3V"
VALUE"2.2UF"
$LOCATION"C59"
CDS_LIB"pure_quanta"
CDS_LOCATION"C59"
$SEC"1"
CDS_SEC"1";
"B"
$PN"2"5;
"A"
$PN"1"1;
%"VCC_CORE"
"1","(-900,1100)","0","logical_power","I122";
;
HDL_POWER"P3V3_AUX"
CDS_LIB"logical_power";
"A"1;
%"Q_CAP"
"1","(100,775)","0","pure_quanta","I125";
;
PART_NUMBER"CH6103KEA00"
TOLERANCE"10%"
VALUE"10UF"
PACK_TYPE"C0805"
VOLTAGE"16V"
MATERIAL"X6S"
$LOCATION"C60"
CDS_LIB"pure_quanta"
CDS_LOCATION"C60"
$SEC"1"
CDS_SEC"1";
"B"
$PN"2"6;
"A"
$PN"1"2;
%"VCC_CORE"
"1","(100,1100)","0","logical_power","I126";
;
HDL_POWER"P12V_S3_AUX_CPU1_NVDIMM"
CDS_LIB"logical_power";
"A"2;
%"Q_CAP"
"1","(725,775)","0","pure_quanta","I127";
;
PART_NUMBER"CH6103KEA00"
TOLERANCE"10%"
VALUE"10UF"
PACK_TYPE"C0805"
VOLTAGE"16V"
MATERIAL"X6S"
$LOCATION"C61"
CDS_LIB"pure_quanta"
CDS_LOCATION"C61"
$SEC"1"
CDS_SEC"1";
"B"
$PN"2"6;
"A"
$PN"1"2;
%"UNIVERSAL_GND"
"1","(725,400)","0","logical_power","I128";
;
HDL_POWER"GND"
CDS_LIB"logical_power";
"A"6;
%"UNIVERSAL_GND"
"1","(1800,950)","0","logical_power","I129";
;
HDL_POWER"GND"
CDS_LIB"logical_power";
"A"7;
%"TAP"
"1","(125,2700)","0","standard","I130";
;
CDS_LIB"standard"
BODY_TYPE"PLUMBING"
HDL_TAP"TRUE";
"B \NAC \NWC"16;
"S \NAC"
BN"0"68;
%"TAP"
"1","(125,2800)","0","standard","I131";
;
CDS_LIB"standard"
BODY_TYPE"PLUMBING"
HDL_TAP"TRUE";
"B \NAC \NWC"16;
"S \NAC"
BN"1"67;
%"TAP"
"1","(300,2750)","0","standard","I132";
;
CDS_LIB"standard"
BODY_TYPE"PLUMBING"
HDL_TAP"TRUE";
"B \NAC \NWC"18;
"S \NAC"
BN"1"47;
%"TAP"
"1","(300,2650)","0","standard","I133";
;
CDS_LIB"standard"
BODY_TYPE"PLUMBING"
HDL_TAP"TRUE";
"B \NAC \NWC"18;
"S \NAC"
BN"0"48;
%"TAP"
"1","(125,2900)","0","standard","I134";
;
CDS_LIB"standard"
BODY_TYPE"PLUMBING"
HDL_TAP"TRUE";
"B \NAC \NWC"16;
"S \NAC"
BN"2"66;
%"TAP"
"1","(125,3000)","0","standard","I135";
;
CDS_LIB"standard"
BODY_TYPE"PLUMBING"
HDL_TAP"TRUE";
"B \NAC \NWC"16;
"S \NAC"
BN"3"65;
%"TAP"
"1","(300,2850)","0","standard","I136";
;
CDS_LIB"standard"
BODY_TYPE"PLUMBING"
HDL_TAP"TRUE";
"B \NAC \NWC"18;
"S \NAC"
BN"2"46;
%"TAP"
"1","(300,3050)","0","standard","I137";
;
CDS_LIB"standard"
BODY_TYPE"PLUMBING"
HDL_TAP"TRUE";
"B \NAC \NWC"18;
"S \NAC"
BN"4"44;
%"TAP"
"1","(300,2950)","0","standard","I138";
;
CDS_LIB"standard"
BODY_TYPE"PLUMBING"
HDL_TAP"TRUE";
"B \NAC \NWC"18;
"S \NAC"
BN"3"45;
%"TAP"
"1","(125,3100)","0","standard","I139";
;
CDS_LIB"standard"
BODY_TYPE"PLUMBING"
HDL_TAP"TRUE";
"B \NAC \NWC"16;
"S \NAC"
BN"4"64;
%"TAP"
"1","(125,3200)","0","standard","I140";
;
CDS_LIB"standard"
BODY_TYPE"PLUMBING"
HDL_TAP"TRUE";
"B \NAC \NWC"16;
"S \NAC"
BN"5"63;
%"TAP"
"1","(125,3300)","0","standard","I141";
;
CDS_LIB"standard"
BODY_TYPE"PLUMBING"
HDL_TAP"TRUE";
"B \NAC \NWC"16;
"S \NAC"
BN"6"62;
%"TAP"
"1","(300,3150)","0","standard","I142";
;
CDS_LIB"standard"
BODY_TYPE"PLUMBING"
HDL_TAP"TRUE";
"B \NAC \NWC"18;
"S \NAC"
BN"5"43;
%"TAP"
"1","(300,3250)","0","standard","I143";
;
CDS_LIB"standard"
BODY_TYPE"PLUMBING"
HDL_TAP"TRUE";
"B \NAC \NWC"18;
"S \NAC"
BN"6"42;
%"TAP"
"1","(125,3400)","0","standard","I144";
;
CDS_LIB"standard"
BODY_TYPE"PLUMBING"
HDL_TAP"TRUE";
"B \NAC \NWC"16;
"S \NAC"
BN"7"61;
%"TAP"
"1","(125,3500)","0","standard","I145";
;
CDS_LIB"standard"
BODY_TYPE"PLUMBING"
HDL_TAP"TRUE";
"B \NAC \NWC"16;
"S \NAC"
BN"8"60;
%"TAP"
"1","(300,3350)","0","standard","I146";
;
CDS_LIB"standard"
BODY_TYPE"PLUMBING"
HDL_TAP"TRUE";
"B \NAC \NWC"18;
"S \NAC"
BN"7"41;
%"TAP"
"1","(300,3450)","0","standard","I147";
;
CDS_LIB"standard"
BODY_TYPE"PLUMBING"
HDL_TAP"TRUE";
"B \NAC \NWC"18;
"S \NAC"
BN"8"40;
%"TAP"
"1","(300,3550)","0","standard","I148";
;
CDS_LIB"standard"
BODY_TYPE"PLUMBING"
HDL_TAP"TRUE";
"B \NAC \NWC"18;
"S \NAC"
BN"9"39;
%"TAP"
"1","(125,3600)","0","standard","I149";
;
CDS_LIB"standard"
BODY_TYPE"PLUMBING"
HDL_TAP"TRUE";
"B \NAC \NWC"16;
"S \NAC"
BN"9"59;
%"TAP"
"1","(125,3750)","0","standard","I150";
;
CDS_LIB"standard"
BODY_TYPE"PLUMBING"
HDL_TAP"TRUE";
"B \NAC \NWC"17;
"S \NAC"
BN"0"58;
%"TAP"
"1","(300,3800)","0","standard","I151";
;
CDS_LIB"standard"
BODY_TYPE"PLUMBING"
HDL_TAP"TRUE";
"B \NAC \NWC"19;
"S \NAC"
BN"1"37;
%"TAP"
"1","(300,3700)","0","standard","I152";
;
CDS_LIB"standard"
BODY_TYPE"PLUMBING"
HDL_TAP"TRUE";
"B \NAC \NWC"19;
"S \NAC"
BN"0"38;
%"TAP"
"1","(125,3850)","0","standard","I153";
;
CDS_LIB"standard"
BODY_TYPE"PLUMBING"
HDL_TAP"TRUE";
"B \NAC \NWC"17;
"S \NAC"
BN"1"57;
%"TAP"
"1","(125,3950)","0","standard","I154";
;
CDS_LIB"standard"
BODY_TYPE"PLUMBING"
HDL_TAP"TRUE";
"B \NAC \NWC"17;
"S \NAC"
BN"2"56;
%"TAP"
"1","(125,4050)","0","standard","I155";
;
CDS_LIB"standard"
BODY_TYPE"PLUMBING"
HDL_TAP"TRUE";
"B \NAC \NWC"17;
"S \NAC"
BN"3"55;
%"TAP"
"1","(300,3900)","0","standard","I156";
;
CDS_LIB"standard"
BODY_TYPE"PLUMBING"
HDL_TAP"TRUE";
"B \NAC \NWC"19;
"S \NAC"
BN"2"36;
%"TAP"
"1","(300,4000)","0","standard","I157";
;
CDS_LIB"standard"
BODY_TYPE"PLUMBING"
HDL_TAP"TRUE";
"B \NAC \NWC"19;
"S \NAC"
BN"3"35;
%"TAP"
"1","(125,4150)","0","standard","I158";
;
CDS_LIB"standard"
BODY_TYPE"PLUMBING"
HDL_TAP"TRUE";
"B \NAC \NWC"17;
"S \NAC"
BN"4"54;
%"TAP"
"1","(125,4250)","0","standard","I159";
;
CDS_LIB"standard"
BODY_TYPE"PLUMBING"
HDL_TAP"TRUE";
"B \NAC \NWC"17;
"S \NAC"
BN"5"53;
%"TAP"
"1","(300,4300)","0","standard","I160";
;
CDS_LIB"standard"
BODY_TYPE"PLUMBING"
HDL_TAP"TRUE";
"B \NAC \NWC"19;
"S \NAC"
BN"6"32;
%"TAP"
"1","(300,4200)","0","standard","I161";
;
CDS_LIB"standard"
BODY_TYPE"PLUMBING"
HDL_TAP"TRUE";
"B \NAC \NWC"19;
"S \NAC"
BN"5"33;
%"TAP"
"1","(300,4100)","0","standard","I162";
;
CDS_LIB"standard"
BODY_TYPE"PLUMBING"
HDL_TAP"TRUE";
"B \NAC \NWC"19;
"S \NAC"
BN"4"34;
%"TAP"
"1","(125,4350)","0","standard","I166";
;
CDS_LIB"standard"
BODY_TYPE"PLUMBING"
HDL_TAP"TRUE";
"B \NAC \NWC"17;
"S \NAC"
BN"6"52;
%"TAP"
"1","(125,4450)","0","standard","I167";
;
CDS_LIB"standard"
BODY_TYPE"PLUMBING"
HDL_TAP"TRUE";
"B \NAC \NWC"17;
"S \NAC"
BN"7"51;
%"TAP"
"1","(125,4550)","0","standard","I168";
;
CDS_LIB"standard"
BODY_TYPE"PLUMBING"
HDL_TAP"TRUE";
"B \NAC \NWC"17;
"S \NAC"
BN"8"50;
%"TAP"
"1","(300,4400)","0","standard","I169";
;
CDS_LIB"standard"
BODY_TYPE"PLUMBING"
HDL_TAP"TRUE";
"B \NAC \NWC"19;
"S \NAC"
BN"7"31;
%"TAP"
"1","(300,4500)","0","standard","I170";
;
CDS_LIB"standard"
BODY_TYPE"PLUMBING"
HDL_TAP"TRUE";
"B \NAC \NWC"19;
"S \NAC"
BN"8"29;
%"TAP"
"1","(300,4600)","0","standard","I171";
;
CDS_LIB"standard"
BODY_TYPE"PLUMBING"
HDL_TAP"TRUE";
"B \NAC \NWC"19;
"S \NAC"
BN"9"30;
%"TAP"
"1","(125,4650)","0","standard","I172";
;
CDS_LIB"standard"
BODY_TYPE"PLUMBING"
HDL_TAP"TRUE";
"B \NAC \NWC"17;
"S \NAC"
BN"9"49;
%"VCC_CORE"
"1","(1800,5200)","0","logical_power","I175";
;
HDL_POWER"P12V_S3_AUX_CPU1_NVDIMM"
CDS_LIB"logical_power";
"A"3;
%"SCONN288_ADR50017P087CC"
"3","(2650,3025)","0","pure_quanta","I176";
;
PART_NUMBER"DFHST8FS460"
MATERIAL"IO"
PART_TYPE"SMLF"
VALUE"SCONN288_ADR50017-P087CC"
$LOCATION"J20"
NEEDS_NO_SIZE"TRUE"
CDS_LMAN_SYM_OUTLINE"-450,1775,450,-1775"
CDS_LIB"pure_quanta"
CDS_LOCATION"J20"
$SEC"3"
CDS_SEC"3";
"G3"
$PN"G3"8;
"G2"
$PN"G2"8;
"G1"
$PN"G1"8;
"VSS62"
$PN"141"8;
"VSS61"
$PN"139"8;
"VSS60"
$PN"136"8;
"VSS58"
$PN"132"8;
"VSS104"
$PN"240"7;
"VSS102"
$PN"235"7;
"VSS100"
$PN"230"7;
"VIN_BULK2"
$PN"146"3;
"VIN_BULK1"
$PN"145"3;
"VIN_BULK0"
$PN"1"3;
"VSS126"
$PN"288"7;
"VSS125"
$PN"286"7;
"VSS124"
$PN"284"7;
"VSS123"
$PN"281"7;
"VSS122"
$PN"279"7;
"VSS121"
$PN"277"7;
"VSS120"
$PN"275"7;
"VSS119"
$PN"273"7;
"VSS118"
$PN"270"7;
"VSS117"
$PN"268"7;
"VSS116"
$PN"266"7;
"VSS115"
$PN"264"7;
"VSS114"
$PN"262"7;
"VSS113"
$PN"259"7;
"VSS112"
$PN"257"7;
"VSS111"
$PN"255"7;
"VSS110"
$PN"253"7;
"VSS109"
$PN"251"7;
"VSS108"
$PN"248"7;
"VSS107"
$PN"246"7;
"VSS106"
$PN"244"7;
"VSS105"
$PN"242"7;
"VSS103"
$PN"237"7;
"VSS101"
$PN"233"7;
"VSS99"
$PN"228"7;
"VSS98"
$PN"226"7;
"VSS97"
$PN"224"7;
"VSS96"
$PN"222"7;
"VSS95"
$PN"219"7;
"VSS94"
$PN"216"7;
"VSS93"
$PN"214"7;
"VSS92"
$PN"212"7;
"VSS91"
$PN"210"7;
"VSS90"
$PN"208"7;
"VSS89"
$PN"206"7;
"VSS88"
$PN"204"7;
"VSS87"
$PN"202"7;
"VSS86"
$PN"199"7;
"VSS85"
$PN"197"7;
"VSS84"
$PN"195"7;
"VSS83"
$PN"193"7;
"VSS82"
$PN"191"7;
"VSS81"
$PN"188"7;
"VSS80"
$PN"186"7;
"VSS79"
$PN"184"7;
"VSS78"
$PN"182"7;
"VSS77"
$PN"180"7;
"VSS76"
$PN"177"7;
"VSS75"
$PN"175"7;
"VSS74"
$PN"173"7;
"VSS73"
$PN"171"7;
"VSS72"
$PN"169"7;
"VSS71"
$PN"166"7;
"VSS70"
$PN"164"7;
"VSS69"
$PN"162"7;
"VSS68"
$PN"160"7;
"VSS67"
$PN"158"7;
"VSS66"
$PN"155"7;
"VSS65"
$PN"153"7;
"VSS64"
$PN"151"7;
"VSS63"
$PN"143"8;
"VSS59"
$PN"134"8;
"VSS57"
$PN"130"8;
"VSS56"
$PN"128"8;
"VSS55"
$PN"125"8;
"VSS54"
$PN"123"8;
"VSS53"
$PN"121"8;
"VSS52"
$PN"119"8;
"VSS51"
$PN"117"8;
"VSS50"
$PN"114"8;
"VSS49"
$PN"112"8;
"VSS48"
$PN"110"8;
"VSS47"
$PN"108"8;
"VSS46"
$PN"106"8;
"VSS45"
$PN"103"8;
"VSS44"
$PN"101"8;
"VSS43"
$PN"99"8;
"VSS42"
$PN"97"8;
"VSS41"
$PN"95"8;
"VSS40"
$PN"92"8;
"VSS39"
$PN"90"8;
"VSS38"
$PN"88"8;
"VSS37"
$PN"85"8;
"VSS36"
$PN"83"8;
"VSS35"
$PN"81"8;
"VSS34"
$PN"79"8;
"VSS33"
$PN"77"8;
"VSS32"
$PN"75"8;
"VSS31"
$PN"73"8;
"VSS30"
$PN"71"8;
"VSS29"
$PN"69"8;
"VSS28"
$PN"67"8;
"VSS27"
$PN"65"8;
"VSS26"
$PN"63"8;
"VSS25"
$PN"61"8;
"VSS24"
$PN"59"8;
"VSS23"
$PN"57"8;
"VSS22"
$PN"54"8;
"VSS21"
$PN"52"8;
"VSS20"
$PN"50"8;
"VSS19"
$PN"48"8;
"VSS18"
$PN"46"8;
"VSS17"
$PN"43"8;
"VSS16"
$PN"41"8;
"VSS15"
$PN"39"8;
"VSS14"
$PN"37"8;
"VSS13"
$PN"35"8;
"VSS12"
$PN"32"8;
"VSS11"
$PN"30"8;
"VSS10"
$PN"28"8;
"VSS9"
$PN"26"8;
"VSS8"
$PN"24"8;
"VSS7"
$PN"21"8;
"VSS6"
$PN"19"8;
"VSS5"
$PN"17"8;
"VSS4"
$PN"15"8;
"VSS3"
$PN"13"8;
"VSS2"
$PN"10"8;
"VSS1"
$PN"8"8;
"VSS0"
$PN"6"8;
%"UNIVERSAL_GND"
"1","(3500,950)","0","logical_power","I177";
;
HDL_POWER"GND"
CDS_LIB"logical_power";
"A"8;
%"SCONN288_ADR50017P087CC"
"2","(-775,3650)","0","pure_quanta","I178";
;
PART_NUMBER"DFHST8FS460"
PART_TYPE"SMLF"
MATERIAL"IO"
VALUE"SCONN288_ADR50017-P087CC"
LOCATION"J20"
NEEDS_NO_SIZE"TRUE"
CDS_LMAN_SYM_OUTLINE"-600,1150,600,-1150"
CDS_LIB"pure_quanta"
$SEC"2"
CDS_SEC"2";
"DQS7_A_C||TDQS7_A_C \B"
$PN"178"31;
"DQS6_A_T||TDQS6_A_T"
$PN"168"52;
"DQS8_B_T||TDQS8_B_T"
$PN"283"60;
"DQS8_B_C||TDQS8_B_C \B"
$PN"282"40;
"DQS7_B_T||TDQS7_B_T"
$PN"272"61;
"DQS0_A_C \B"
$PN"12"38;
"DQS0_A_T"
$PN"11"58;
"DQS0_B_C \B"
$PN"105"48;
"DQS0_B_T"
$PN"104"68;
"DQS1_A_C \B"
$PN"23"37;
"DQS1_A_T"
$PN"22"57;
"DQS1_B_C \B"
$PN"116"47;
"DQS1_B_T"
$PN"115"67;
"DQS2_A_C \B"
$PN"34"36;
"DQS2_A_T"
$PN"33"56;
"DQS2_B_C \B"
$PN"127"46;
"DQS2_B_T"
$PN"126"66;
"DQS3_A_C \B"
$PN"45"35;
"DQS3_A_T"
$PN"44"55;
"DQS3_B_C \B"
$PN"138"45;
"DQS3_B_T"
$PN"137"65;
"DQS4_A_C \B"
$PN"56"34;
"DQS4_A_T"
$PN"55"54;
"DQS4_B_C \B"
$PN"238"44;
"DQS4_B_T"
$PN"239"64;
"DQS5_A_C||TDQS5_A_C||DQS5_A_T||TDQS5_A_T \B"
$PN"156"33;
"DQS5_A_T||TDQS5_A_T"
$PN"157"53;
"DQS5_B_C||TDQS5_B_C \B"
$PN"249"43;
"DQS5_B_T||TDQS5_B_T"
$PN"250"63;
"DQS6_A_C||TDQS6_A_C||DQS6_A_T||TDQS6_A_T \B"
$PN"167"32;
"DQS6_B_C||TDQS6_B_C \B"
$PN"260"42;
"DQS6_B_T||TDQS6_B_T"
$PN"261"62;
"DQS7_A_T||TDQS7_A_T"
$PN"179"51;
"DQS7_B_C||TDQS7_B_C \B"
$PN"271"41;
"DQS8_A_C||TDQS8_A_C \B"
$PN"189"29;
"DQS8_A_T||TDQS8_A_T"
$PN"190"50;
"DQS9_A_C||TDQS9_A_C \B"
$PN"200"30;
"DQS9_A_T||TDQS9_A_T"
$PN"201"49;
"DQS9_B_C||TDQS9_B_C \B"
$PN"94"39;
"DQS9_B_T||TDQS9_B_T||DBI4_B_N"
$PN"93"59;
%"Q_RES"
"1","(-5275,1950)","0","pure_quanta","I180";
;
PART_NUMBER"CS04992FB07"
VALUE"49.9"
MATERIAL"CHIP"
$LOCATION"R3894"
CDS_LIB"pure_quanta"
PACK_TYPE"0402LF"
TOLERANCE"1%"
WATTAGE"1/16W"
CDS_LOCATION"R3894"
$SEC"1"
CDS_SEC"1";
"B"
$PN"2"20;
"A"
$PN"1"23;
%"VCC_CORE"
"1","(-5100,2525)","0","logical_power","I21";
;
HDL_POWER"P3V3_AUX"
CDS_LIB"logical_power";
"A"4;
%"TAP"
"1","(-4275,2450)","2","standard","I22";
;
CDS_LIB"standard"
BODY_TYPE"PLUMBING"
HDL_TAP"TRUE";
"B \NAC \NWC"12;
"S \NAC"
BN"0"148;
%"TAP"
"1","(-4275,2500)","2","standard","I23";
;
CDS_LIB"standard"
BODY_TYPE"PLUMBING"
HDL_TAP"TRUE";
"B \NAC \NWC"12;
"S \NAC"
BN"1"149;
%"TAP"
"1","(-4275,2550)","2","standard","I24";
;
CDS_LIB"standard"
BODY_TYPE"PLUMBING"
HDL_TAP"TRUE";
"B \NAC \NWC"12;
"S \NAC"
BN"2"150;
%"TAP"
"1","(-4275,2600)","2","standard","I25";
;
CDS_LIB"standard"
BODY_TYPE"PLUMBING"
HDL_TAP"TRUE";
"B \NAC \NWC"12;
"S \NAC"
BN"3"69;
%"TAP"
"1","(-4275,2650)","2","standard","I26";
;
CDS_LIB"standard"
BODY_TYPE"PLUMBING"
HDL_TAP"TRUE";
"B \NAC \NWC"12;
"S \NAC"
BN"4"151;
%"TAP"
"1","(-4275,2700)","2","standard","I27";
;
CDS_LIB"standard"
BODY_TYPE"PLUMBING"
HDL_TAP"TRUE";
"B \NAC \NWC"12;
"S \NAC"
BN"5"152;
%"TAP"
"1","(-4275,2750)","2","standard","I28";
;
CDS_LIB"standard"
BODY_TYPE"PLUMBING"
HDL_TAP"TRUE";
"B \NAC \NWC"12;
"S \NAC"
BN"6"153;
%"TAP"
"1","(-4275,2800)","2","standard","I29";
;
CDS_LIB"standard"
BODY_TYPE"PLUMBING"
HDL_TAP"TRUE";
"B \NAC \NWC"12;
"S \NAC"
BN"7"173;
%"TAP"
"1","(-4275,2900)","2","standard","I30";
;
CDS_LIB"standard"
BODY_TYPE"PLUMBING"
HDL_TAP"TRUE";
"B \NAC \NWC"11;
"S \NAC"
BN"0"154;
%"TAP"
"1","(-4275,3000)","2","standard","I31";
;
CDS_LIB"standard"
BODY_TYPE"PLUMBING"
HDL_TAP"TRUE";
"B \NAC \NWC"11;
"S \NAC"
BN"2"155;
%"TAP"
"1","(-4275,2950)","2","standard","I32";
;
CDS_LIB"standard"
BODY_TYPE"PLUMBING"
HDL_TAP"TRUE";
"B \NAC \NWC"11;
"S \NAC"
BN"1"174;
%"TAP"
"1","(-4275,3050)","2","standard","I33";
;
CDS_LIB"standard"
BODY_TYPE"PLUMBING"
HDL_TAP"TRUE";
"B \NAC \NWC"11;
"S \NAC"
BN"3"156;
%"TAP"
"1","(-4275,3100)","2","standard","I34";
;
CDS_LIB"standard"
BODY_TYPE"PLUMBING"
HDL_TAP"TRUE";
"B \NAC \NWC"11;
"S \NAC"
BN"4"175;
%"TAP"
"1","(-4275,3150)","2","standard","I35";
;
CDS_LIB"standard"
BODY_TYPE"PLUMBING"
HDL_TAP"TRUE";
"B \NAC \NWC"11;
"S \NAC"
BN"5"157;
%"TAP"
"1","(-4275,3200)","2","standard","I36";
;
CDS_LIB"standard"
BODY_TYPE"PLUMBING"
HDL_TAP"TRUE";
"B \NAC \NWC"11;
"S \NAC"
BN"6"158;
%"TAP"
"1","(-4275,3250)","2","standard","I37";
;
CDS_LIB"standard"
BODY_TYPE"PLUMBING"
HDL_TAP"TRUE";
"B \NAC \NWC"11;
"S \NAC"
BN"7"176;
%"TAP"
"1","(-4275,3950)","2","standard","I38";
;
CDS_LIB"standard"
BODY_TYPE"PLUMBING"
HDL_TAP"TRUE";
"B \NAC \NWC"14;
"S \NAC"
BN"0"171;
%"TAP"
"1","(-4275,4000)","2","standard","I39";
;
CDS_LIB"standard"
BODY_TYPE"PLUMBING"
HDL_TAP"TRUE";
"B \NAC \NWC"14;
"S \NAC"
BN"1"169;
%"TAP"
"1","(-4275,4050)","2","standard","I40";
;
CDS_LIB"standard"
BODY_TYPE"PLUMBING"
HDL_TAP"TRUE";
"B \NAC \NWC"14;
"S \NAC"
BN"2"167;
%"TAP"
"1","(-4275,4150)","2","standard","I41";
;
CDS_LIB"standard"
BODY_TYPE"PLUMBING"
HDL_TAP"TRUE";
"B \NAC \NWC"14;
"S \NAC"
BN"4"163;
%"TAP"
"1","(-4275,4250)","2","standard","I42";
;
CDS_LIB"standard"
BODY_TYPE"PLUMBING"
HDL_TAP"TRUE";
"B \NAC \NWC"14;
"S \NAC"
BN"6"159;
%"TAP"
"1","(-4275,4200)","2","standard","I43";
;
CDS_LIB"standard"
BODY_TYPE"PLUMBING"
HDL_TAP"TRUE";
"B \NAC \NWC"14;
"S \NAC"
BN"5"161;
%"TAP"
"1","(-4275,4100)","2","standard","I44";
;
CDS_LIB"standard"
BODY_TYPE"PLUMBING"
HDL_TAP"TRUE";
"B \NAC \NWC"14;
"S \NAC"
BN"3"165;
%"UNIVERSAL_GND"
"1","(-4050,275)","0","logical_power","I45";
;
HDL_POWER"GND"
CDS_LIB"logical_power";
"A"9;
%"Q_RES"
"2","(-4050,500)","0","pure_quanta","I46";
;
PART_NUMBER"CS33572FB01"
VALUE"35.7K"
MATERIAL"CHIP"
PACK_TYPE"0402LF"
WATTAGE"1/16W"
TOLERANCE"1%"
$LOCATION"R45"
CDS_LIB"pure_quanta"
CDS_LOCATION"R45"
$SEC"1"
CDS_SEC"1";
"A"
$PN"1"178;
"B"
$PN"2"9;
%"SCONN288_ADR50017P087CC"
"1","(-3450,2925)","0","pure_quanta","I47";
;
PART_NUMBER"DFHST8FS460"
MATERIAL"IO"
VALUE"SCONN288_ADR50017-P087CC"
PART_TYPE"SMLF"
$LOCATION"J20"
NEEDS_NO_SIZE"TRUE"
CDS_LMAN_SYM_OUTLINE"-450,1875,450,-1875"
CDS_LIB"pure_quanta"
CDS_LOCATION"J20"
$SEC"1"
CDS_SEC"1";
"DQ31_A"
$PN"194"177;
"CB7_A"
$PN"205"176;
"CB4_A"
$PN"58"175;
"CB1_A"
$PN"53"174;
"CB7_B"
$PN"236"173;
"ALERT_N \B"
$PN"62"24;
"CA0_A"
$PN"66"172;
"CA0_B"
$PN"76"171;
"CA1_A"
$PN"211"170;
"CA1_B"
$PN"221"169;
"CA2_A"
$PN"68"168;
"CA2_B"
$PN"78"167;
"CA3_A"
$PN"213"166;
"CA3_B"
$PN"223"165;
"CA4_A"
$PN"70"164;
"CA4_B"
$PN"80"163;
"CA5_A"
$PN"215"162;
"CA5_B"
$PN"225"161;
"CA6_A"
$PN"72"160;
"CA6_B"
$PN"82"159;
"CB6_A"
$PN"203"158;
"CB5_A"
$PN"60"157;
"CB3_A"
$PN"198"156;
"CB2_A"
$PN"196"155;
"CB0_A"
$PN"51"154;
"CB6_B"
$PN"234"153;
"CB5_B"
$PN"91"152;
"CB4_B"
$PN"89"151;
"CB3_B"
$PN"243"69;
"CB2_B"
$PN"241"150;
"CB1_B"
$PN"98"149;
"CB0_B"
$PN"96"148;
"CK_C \B"
$PN"218"147;
"CK_T"
$PN"217"146;
"CS0_A_N"
$PN"64"145;
"CS0_B_N"
$PN"84"144;
"CS1_A_N"
$PN"209"143;
"CS1_B_N"
$PN"229"142;
"DQ30_A"
$PN"192"141;
"DQ29_A"
$PN"49"140;
"DQ28_A"
$PN"47"139;
"DQ27_A"
$PN"187"138;
"DQ26_A"
$PN"185"137;
"DQ25_A"
$PN"42"136;
"DQ24_A"
$PN"40"135;
"DQ23_A"
$PN"183"134;
"DQ22_A"
$PN"181"133;
"DQ21_A"
$PN"38"72;
"DQ20_A"
$PN"36"73;
"DQ19_A"
$PN"176"74;
"DQ18_A"
$PN"174"132;
"DQ17_A"
$PN"31"131;
"DQ16_A"
$PN"29"130;
"DQ15_A"
$PN"172"129;
"DQ14_A"
$PN"170"128;
"DQ13_A"
$PN"27"127;
"DQ12_A"
$PN"25"126;
"DQ11_A"
$PN"165"125;
"DQ10_A"
$PN"163"124;
"DQ9_A"
$PN"20"123;
"DQ8_A"
$PN"18"76;
"DQ7_A"
$PN"161"75;
"DQ6_A"
$PN"159"122;
"DQ5_A"
$PN"16"121;
"DQ4_A"
$PN"14"120;
"DQ3_A"
$PN"154"119;
"DQ2_A"
$PN"152"118;
"DQ1_A"
$PN"9"117;
"DQ0_A"
$PN"7"116;
"DQ31_B"
$PN"287"115;
"DQ30_B"
$PN"285"114;
"DQ29_B"
$PN"142"113;
"DQ28_B"
$PN"140"112;
"DQ27_B"
$PN"280"111;
"DQ26_B"
$PN"278"110;
"DQ25_B"
$PN"135"109;
"DQ24_B"
$PN"133"108;
"DQ23_B"
$PN"276"107;
"DQ22_B"
$PN"274"106;
"DQ21_B"
$PN"131"105;
"DQ20_B"
$PN"129"104;
"DQ19_B"
$PN"269"103;
"DQ18_B"
$PN"267"102;
"DQ17_B"
$PN"124"101;
"DQ16_B"
$PN"122"71;
"DQ15_B"
$PN"265"100;
"DQ14_B"
$PN"263"77;
"DQ13_B"
$PN"120"70;
"DQ12_B"
$PN"118"78;
"DQ11_B"
$PN"258"99;
"DQ10_B"
$PN"256"98;
"DQ9_B"
$PN"113"97;
"DQ8_B"
$PN"111"96;
"DQ7_B"
$PN"254"95;
"DQ6_B"
$PN"252"94;
"DQ5_B"
$PN"109"93;
"DQ4_B"
$PN"107"92;
"DQ3_B"
$PN"247"91;
"DQ2_B"
$PN"245"90;
"DQ1_B"
$PN"102"89;
"DQ0_B"
$PN"100"88;
"HSA"
$PN"148"21;
"HSCL"
$PN"4"23;
"HSDA"
$PN"5"22;
"LBD||RSP_A_N"
$PN"86"87;
"LBS||RSP_B_N"
$PN"87"86;
"PAR_A"
$PN"74"85;
"PAR_B"
$PN"227"84;
"PWR_GOOD||FAIL_N"
$PN"147"26;
"RESET_N \B"
$PN"207"25;
"RFU6"
$PN"232"27;
"RFU5"
$PN"231"28;
"RFU4"
$PN"220"83;
"RFU3"
$PN"150"82;
"RFU2"
$PN"149"81;
"RFU1"
$PN"144"80;
"RFU0"
$PN"2"79;
"VIN_MGMT"
$PN"3"4;
%"TAP"
"1","(-2625,1450)","0","standard","I48";
;
CDS_LIB"standard"
BODY_TYPE"PLUMBING"
HDL_TAP"TRUE";
"B \NAC \NWC"15;
"S \NAC"
BN"0"88;
%"TAP"
"1","(-2625,1500)","0","standard","I49";
;
CDS_LIB"standard"
BODY_TYPE"PLUMBING"
HDL_TAP"TRUE";
"B \NAC \NWC"15;
"S \NAC"
BN"1"89;
%"TAP"
"1","(-2625,1550)","0","standard","I50";
;
CDS_LIB"standard"
BODY_TYPE"PLUMBING"
HDL_TAP"TRUE";
"B \NAC \NWC"15;
"S \NAC"
BN"2"90;
%"TAP"
"1","(-2625,1650)","0","standard","I51";
;
CDS_LIB"standard"
BODY_TYPE"PLUMBING"
HDL_TAP"TRUE";
"B \NAC \NWC"15;
"S \NAC"
BN"4"92;
%"TAP"
"1","(-2625,1600)","0","standard","I52";
;
CDS_LIB"standard"
BODY_TYPE"PLUMBING"
HDL_TAP"TRUE";
"B \NAC \NWC"15;
"S \NAC"
BN"3"91;
%"TAP"
"1","(-2625,1750)","0","standard","I53";
;
CDS_LIB"standard"
BODY_TYPE"PLUMBING"
HDL_TAP"TRUE";
"B \NAC \NWC"15;
"S \NAC"
BN"6"94;
%"TAP"
"1","(-2625,1700)","0","standard","I54";
;
CDS_LIB"standard"
BODY_TYPE"PLUMBING"
HDL_TAP"TRUE";
"B \NAC \NWC"15;
"S \NAC"
BN"5"93;
%"TAP"
"1","(-2625,1800)","0","standard","I55";
;
CDS_LIB"standard"
BODY_TYPE"PLUMBING"
HDL_TAP"TRUE";
"B \NAC \NWC"15;
"S \NAC"
BN"7"95;
%"TAP"
"1","(-2625,1850)","0","standard","I56";
;
CDS_LIB"standard"
BODY_TYPE"PLUMBING"
HDL_TAP"TRUE";
"B \NAC \NWC"15;
"S \NAC"
BN"8"96;
%"TAP"
"1","(-2625,1900)","0","standard","I57";
;
CDS_LIB"standard"
BODY_TYPE"PLUMBING"
HDL_TAP"TRUE";
"B \NAC \NWC"15;
"S \NAC"
BN"9"97;
%"TAP"
"1","(-2625,1950)","0","standard","I58";
;
CDS_LIB"standard"
BODY_TYPE"PLUMBING"
HDL_TAP"TRUE";
"B \NAC \NWC"15;
"S \NAC"
BN"10"98;
%"TAP"
"1","(-2625,2000)","0","standard","I59";
;
CDS_LIB"standard"
BODY_TYPE"PLUMBING"
HDL_TAP"TRUE";
"B \NAC \NWC"15;
"S \NAC"
BN"11"99;
%"TAP"
"1","(-2625,2050)","0","standard","I60";
;
CDS_LIB"standard"
BODY_TYPE"PLUMBING"
HDL_TAP"TRUE";
"B \NAC \NWC"15;
"S \NAC"
BN"12"78;
%"TAP"
"1","(-2625,2100)","0","standard","I61";
;
CDS_LIB"standard"
BODY_TYPE"PLUMBING"
HDL_TAP"TRUE";
"B \NAC \NWC"15;
"S \NAC"
BN"13"70;
%"TAP"
"1","(-2625,2150)","0","standard","I62";
;
CDS_LIB"standard"
BODY_TYPE"PLUMBING"
HDL_TAP"TRUE";
"B \NAC \NWC"15;
"S \NAC"
BN"14"77;
%"TAP"
"1","(-2625,2200)","0","standard","I63";
;
CDS_LIB"standard"
BODY_TYPE"PLUMBING"
HDL_TAP"TRUE";
"B \NAC \NWC"15;
"S \NAC"
BN"15"100;
%"TAP"
"1","(-2625,2250)","0","standard","I64";
;
CDS_LIB"standard"
BODY_TYPE"PLUMBING"
HDL_TAP"TRUE";
"B \NAC \NWC"15;
"S \NAC"
BN"16"71;
%"TAP"
"1","(-2625,2300)","0","standard","I65";
;
CDS_LIB"standard"
BODY_TYPE"PLUMBING"
HDL_TAP"TRUE";
"B \NAC \NWC"15;
"S \NAC"
BN"17"101;
%"TAP"
"1","(-2625,2350)","0","standard","I66";
;
CDS_LIB"standard"
BODY_TYPE"PLUMBING"
HDL_TAP"TRUE";
"B \NAC \NWC"15;
"S \NAC"
BN"18"102;
%"TAP"
"1","(-2625,2400)","0","standard","I67";
;
CDS_LIB"standard"
BODY_TYPE"PLUMBING"
HDL_TAP"TRUE";
"B \NAC \NWC"15;
"S \NAC"
BN"19"103;
%"TAP"
"1","(-2625,2450)","0","standard","I68";
;
CDS_LIB"standard"
BODY_TYPE"PLUMBING"
HDL_TAP"TRUE";
"B \NAC \NWC"15;
"S \NAC"
BN"20"104;
%"TAP"
"1","(-2625,2550)","0","standard","I69";
;
CDS_LIB"standard"
BODY_TYPE"PLUMBING"
HDL_TAP"TRUE";
"B \NAC \NWC"15;
"S \NAC"
BN"22"106;
%"TAP"
"1","(-2625,2500)","0","standard","I70";
;
CDS_LIB"standard"
BODY_TYPE"PLUMBING"
HDL_TAP"TRUE";
"B \NAC \NWC"15;
"S \NAC"
BN"21"105;
%"TAP"
"1","(-2625,2600)","0","standard","I71";
;
CDS_LIB"standard"
BODY_TYPE"PLUMBING"
HDL_TAP"TRUE";
"B \NAC \NWC"15;
"S \NAC"
BN"23"107;
%"TAP"
"1","(-2625,2650)","0","standard","I72";
;
CDS_LIB"standard"
BODY_TYPE"PLUMBING"
HDL_TAP"TRUE";
"B \NAC \NWC"15;
"S \NAC"
BN"24"108;
%"TAP"
"1","(-2625,2700)","0","standard","I73";
;
CDS_LIB"standard"
BODY_TYPE"PLUMBING"
HDL_TAP"TRUE";
"B \NAC \NWC"15;
"S \NAC"
BN"25"109;
%"TAP"
"1","(-2625,2800)","0","standard","I74";
;
CDS_LIB"standard"
BODY_TYPE"PLUMBING"
HDL_TAP"TRUE";
"B \NAC \NWC"15;
"S \NAC"
BN"27"111;
%"TAP"
"1","(-2625,2750)","0","standard","I75";
;
CDS_LIB"standard"
BODY_TYPE"PLUMBING"
HDL_TAP"TRUE";
"B \NAC \NWC"15;
"S \NAC"
BN"26"110;
%"TAP"
"1","(-2625,2850)","0","standard","I76";
;
CDS_LIB"standard"
BODY_TYPE"PLUMBING"
HDL_TAP"TRUE";
"B \NAC \NWC"15;
"S \NAC"
BN"28"112;
%"TAP"
"1","(-2625,2900)","0","standard","I77";
;
CDS_LIB"standard"
BODY_TYPE"PLUMBING"
HDL_TAP"TRUE";
"B \NAC \NWC"15;
"S \NAC"
BN"29"113;
%"TAP"
"1","(-2625,3000)","0","standard","I78";
;
CDS_LIB"standard"
BODY_TYPE"PLUMBING"
HDL_TAP"TRUE";
"B \NAC \NWC"15;
"S \NAC"
BN"31"115;
%"TAP"
"1","(-2625,2950)","0","standard","I79";
;
CDS_LIB"standard"
BODY_TYPE"PLUMBING"
HDL_TAP"TRUE";
"B \NAC \NWC"15;
"S \NAC"
BN"30"114;
%"TAP"
"1","(-2625,3150)","0","standard","I80";
;
CDS_LIB"standard"
BODY_TYPE"PLUMBING"
HDL_TAP"TRUE";
"B \NAC \NWC"10;
"S \NAC"
BN"1"117;
%"TAP"
"1","(-2625,3100)","0","standard","I81";
;
CDS_LIB"standard"
BODY_TYPE"PLUMBING"
HDL_TAP"TRUE";
"B \NAC \NWC"10;
"S \NAC"
BN"0"116;
%"TAP"
"1","(-2625,3250)","0","standard","I82";
;
CDS_LIB"standard"
BODY_TYPE"PLUMBING"
HDL_TAP"TRUE";
"B \NAC \NWC"10;
"S \NAC"
BN"3"119;
%"TAP"
"1","(-2625,3200)","0","standard","I83";
;
CDS_LIB"standard"
BODY_TYPE"PLUMBING"
HDL_TAP"TRUE";
"B \NAC \NWC"10;
"S \NAC"
BN"2"118;
%"TAP"
"1","(-2625,3300)","0","standard","I84";
;
CDS_LIB"standard"
BODY_TYPE"PLUMBING"
HDL_TAP"TRUE";
"B \NAC \NWC"10;
"S \NAC"
BN"4"120;
%"TAP"
"1","(-2625,3400)","0","standard","I85";
;
CDS_LIB"standard"
BODY_TYPE"PLUMBING"
HDL_TAP"TRUE";
"B \NAC \NWC"10;
"S \NAC"
BN"6"122;
%"TAP"
"1","(-2625,3350)","0","standard","I86";
;
CDS_LIB"standard"
BODY_TYPE"PLUMBING"
HDL_TAP"TRUE";
"B \NAC \NWC"10;
"S \NAC"
BN"5"121;
%"TAP"
"1","(-2625,3450)","0","standard","I87";
;
CDS_LIB"standard"
BODY_TYPE"PLUMBING"
HDL_TAP"TRUE";
"B \NAC \NWC"10;
"S \NAC"
BN"7"75;
%"TAP"
"1","(-2625,3550)","0","standard","I88";
;
CDS_LIB"standard"
BODY_TYPE"PLUMBING"
HDL_TAP"TRUE";
"B \NAC \NWC"10;
"S \NAC"
BN"9"123;
%"TAP"
"1","(-2625,3500)","0","standard","I89";
;
CDS_LIB"standard"
BODY_TYPE"PLUMBING"
HDL_TAP"TRUE";
"B \NAC \NWC"10;
"S \NAC"
BN"8"76;
%"TAP"
"1","(-2625,3600)","0","standard","I90";
;
CDS_LIB"standard"
BODY_TYPE"PLUMBING"
HDL_TAP"TRUE";
"B \NAC \NWC"10;
"S \NAC"
BN"10"124;
%"TAP"
"1","(-2625,3700)","0","standard","I91";
;
CDS_LIB"standard"
BODY_TYPE"PLUMBING"
HDL_TAP"TRUE";
"B \NAC \NWC"10;
"S \NAC"
BN"12"126;
%"TAP"
"1","(-2625,3650)","0","standard","I92";
;
CDS_LIB"standard"
BODY_TYPE"PLUMBING"
HDL_TAP"TRUE";
"B \NAC \NWC"10;
"S \NAC"
BN"11"125;
%"TAP"
"1","(-2625,3800)","0","standard","I93";
;
CDS_LIB"standard"
BODY_TYPE"PLUMBING"
HDL_TAP"TRUE";
"B \NAC \NWC"10;
"S \NAC"
BN"14"128;
%"TAP"
"1","(-2625,3750)","0","standard","I94";
;
CDS_LIB"standard"
BODY_TYPE"PLUMBING"
HDL_TAP"TRUE";
"B \NAC \NWC"10;
"S \NAC"
BN"13"127;
%"TAP"
"1","(-2625,3850)","0","standard","I95";
;
CDS_LIB"standard"
BODY_TYPE"PLUMBING"
HDL_TAP"TRUE";
"B \NAC \NWC"10;
"S \NAC"
BN"15"129;
%"TAP"
"1","(-2625,3950)","0","standard","I96";
;
CDS_LIB"standard"
BODY_TYPE"PLUMBING"
HDL_TAP"TRUE";
"B \NAC \NWC"10;
"S \NAC"
BN"17"131;
%"TAP"
"1","(-2625,3900)","0","standard","I97";
;
CDS_LIB"standard"
BODY_TYPE"PLUMBING"
HDL_TAP"TRUE";
"B \NAC \NWC"10;
"S \NAC"
BN"16"130;
%"TAP"
"1","(-2625,4050)","0","standard","I98";
;
CDS_LIB"standard"
BODY_TYPE"PLUMBING"
HDL_TAP"TRUE";
"B \NAC \NWC"10;
"S \NAC"
BN"19"74;
%"TAP"
"1","(-2625,4000)","0","standard","I99";
;
CDS_LIB"standard"
BODY_TYPE"PLUMBING"
HDL_TAP"TRUE";
"B \NAC \NWC"10;
"S \NAC"
BN"18"132;
END.
